(kicad_pcb
	(version 20260206)
	(generator "pcbnew")
	(generator_version "10.0")
	(general
		(thickness 1.6)
		(legacy_teardrops no)
	)
	(paper "A4")
	(title_block
		(title "03242023_DA0F0TMBIJ0_F0T_Motherboard_J_brd_V01_OCP.brd")
		(comment 1 "Grand Teton / footprints 1749-1755 of 6105")
	)
	(layers
		(0 "F.Cu" signal "TOP")
		(4 "In1.Cu" signal "GND")
		(6 "In2.Cu" signal "IN1")
		(8 "In3.Cu" signal "GND1")
		(10 "In4.Cu" signal "IN2")
		(12 "In5.Cu" signal "GND2")
		(14 "In6.Cu" signal "IN3")
		(16 "In7.Cu" signal "GND3")
		(18 "In8.Cu" signal "VCC")
		(20 "In9.Cu" signal "VCC1")
		(22 "In10.Cu" signal "GND4")
		(24 "In11.Cu" signal "IN4")
		(26 "In12.Cu" signal "GND5")
		(28 "In13.Cu" signal "IN5")
		(30 "In14.Cu" signal "GND6")
		(32 "In15.Cu" signal "IN6")
		(34 "In16.Cu" signal "GND7")
		(2 "B.Cu" signal "BOTTOM")
		(9 "F.Adhes" user "F.Adhesive")
		(11 "B.Adhes" user "B.Adhesive")
		(13 "F.Paste" user "Package Geometry/Pastemask Top")
		(15 "B.Paste" user "Package Geometry/Pastemask Bottom")
		(5 "F.SilkS" user "Ref Des/Silkscreen Top")
		(7 "B.SilkS" user "Ref Des/Silkscreen Bottom")
		(1 "F.Mask" user "Board Geometry/Soldermask Top")
		(3 "B.Mask" user "Board Geometry/Soldermask Bottom")
		(17 "Dwgs.User" user "User.Drawings")
		(19 "Cmts.User" user "User.Comments")
		(21 "Eco1.User" user "User.Eco1")
		(23 "Eco2.User" user "User.Eco2")
		(25 "Edge.Cuts" user "Board Geometry/Outline")
		(27 "Margin" user)
		(31 "F.CrtYd" user "Package Geometry/Place Bound Top")
		(29 "B.CrtYd" user "Package Geometry/Place Bound Bottom")
		(35 "F.Fab" user "Ref Des/Assembly Top")
		(33 "B.Fab" user "Ref Des/Assembly Bottom")
	)
	(footprint ""
		(layer "F.Cu")
		(at 240.626392 -250.717558 90)
		(property "Reference" "C2256"
			(at 0 0 90)
			(layer "F.SilkS")
			(hide yes)
			(effects
				(font
					(size 1.27 1.27)
				)
			)
		)
		(property "Value" ""
			(at 0 0 90)
			(layer "F.Fab")
			(effects
				(font
					(size 1.27 1.27)
				)
			)
		)
		(duplicate_pad_numbers_are_jumpers no)
		(fp_line
			(start 0.7874 -0.4064)
			(end 0.7874 0.4064)
			(stroke
				(width 0.1524)
				(type default)
			)
			(layer "F.SilkS")
		)
		(fp_line
			(start -0.7874 -0.4064)
			(end 0.7874 -0.4064)
			(stroke
				(width 0.1524)
				(type default)
			)
			(layer "F.SilkS")
		)
		(fp_line
			(start 0.7874 0.4064)
			(end -0.7874 0.4064)
			(stroke
				(width 0.1524)
				(type default)
			)
			(layer "F.SilkS")
		)
		(fp_line
			(start -0.7874 0.4064)
			(end -0.7874 -0.4064)
			(stroke
				(width 0.1524)
				(type default)
			)
			(layer "F.SilkS")
		)
		(fp_line
			(start -0.12065 -0.305054)
			(end -0.12065 -0.2794)
			(stroke
				(width 0.1)
				(type default)
			)
			(layer "F.Fab")
		)
		(fp_line
			(start -0.67945 -0.305054)
			(end -0.12065 -0.305054)
			(stroke
				(width 0.1)
				(type default)
			)
			(layer "F.Fab")
		)
		(fp_line
			(start 0.67945 -0.3048)
			(end 0.67945 0.3048)
			(stroke
				(width 0.1)
				(type default)
			)
			(layer "F.Fab")
		)
		(fp_line
			(start 0.12065 -0.3048)
			(end 0.67945 -0.3048)
			(stroke
				(width 0.1)
				(type default)
			)
			(layer "F.Fab")
		)
		(fp_line
			(start 0.12065 -0.2794)
			(end 0.12065 -0.3048)
			(stroke
				(width 0.1)
				(type default)
			)
			(layer "F.Fab")
		)
		(fp_line
			(start -0.12065 -0.2794)
			(end 0.12065 -0.2794)
			(stroke
				(width 0.1)
				(type default)
			)
			(layer "F.Fab")
		)
		(fp_line
			(start 0.120396 0.2794)
			(end -0.12065 0.2794)
			(stroke
				(width 0.1)
				(type default)
			)
			(layer "F.Fab")
		)
		(fp_line
			(start -0.12065 0.2794)
			(end -0.12065 0.3048)
			(stroke
				(width 0.1)
				(type default)
			)
			(layer "F.Fab")
		)
		(fp_line
			(start 0.67945 0.3048)
			(end 0.120396 0.3048)
			(stroke
				(width 0.1)
				(type default)
			)
			(layer "F.Fab")
		)
		(fp_line
			(start 0.120396 0.3048)
			(end 0.120396 0.2794)
			(stroke
				(width 0.1)
				(type default)
			)
			(layer "F.Fab")
		)
		(fp_line
			(start -0.12065 0.3048)
			(end -0.67945 0.3048)
			(stroke
				(width 0.1)
				(type default)
			)
			(layer "F.Fab")
		)
		(fp_line
			(start -0.67945 0.3048)
			(end -0.67945 -0.305054)
			(stroke
				(width 0.1)
				(type default)
			)
			(layer "F.Fab")
		)
		(pad "1" smd circle
			(at -0.40005 0 90)
			(size 0 0)
			(layers "F.Cu" "F.Mask" "F.Paste")
			(net "CLK_GEN2_XTAL_OUT")
		)
		(pad "2" smd circle
			(at 0.40005 0 90)
			(size 0 0)
			(layers "F.Cu" "F.Mask" "F.Paste")
			(net "GND")
		)
	)
	(footprint ""
		(layer "F.Cu")
		(at 441.885324 -153.78557)
		(property "Reference" "H120"
			(at -0.79248 -7.30377 0)
			(unlocked yes)
			(layer "F.SilkS")
			(effects
				(font
					(size 0.7874 0.5842)
					(thickness 0.1524)
				)
				(justify left)
			)
		)
		(property "Value" ""
			(at 0 0 0)
			(layer "F.Fab")
			(effects
				(font
					(size 1.27 1.27)
				)
			)
		)
		(duplicate_pad_numbers_are_jumpers no)
		(fp_circle
			(center 0 0)
			(end 5.8166 0)
			(stroke
				(width 0.1524)
				(type default)
			)
			(fill no)
			(layer "F.SilkS")
		)
		(fp_circle
			(center 0 0)
			(end 5.8166 0)
			(stroke
				(width 0.1524)
				(type default)
			)
			(fill no)
			(layer "B.SilkS")
		)
		(fp_circle
			(center 0 0)
			(end 5.8166 0)
			(stroke
				(width 0.1)
				(type default)
			)
			(fill no)
			(layer "B.Fab")
		)
		(fp_circle
			(center 0 0)
			(end 5.8166 0)
			(stroke
				(width 0.1)
				(type default)
			)
			(fill no)
			(layer "F.Fab")
		)
		(pad "" np_thru_hole circle
			(at 0 0)
			(size 10.0076 10.0076)
			(drill 10.0076)
			(layers "*.Cu" "*.Mask")
			(clearance 0.381)
			(thermal_gap 0.381)
		)
	)
	(footprint ""
		(layer "F.Cu")
		(at 54.242716 -111.94669 180)
		(property "Reference" "R3716"
			(at 0 0 180)
			(layer "F.SilkS")
			(hide yes)
			(effects
				(font
					(size 1.27 1.27)
				)
			)
		)
		(property "Value" ""
			(at 0 0 180)
			(layer "F.Fab")
			(effects
				(font
					(size 1.27 1.27)
				)
			)
		)
		(duplicate_pad_numbers_are_jumpers no)
		(fp_line
			(start 0.7874 0.4064)
			(end -0.7874 0.4064)
			(stroke
				(width 0.1524)
				(type default)
			)
			(layer "F.SilkS")
		)
		(fp_line
			(start 0.7874 -0.4064)
			(end 0.7874 0.4064)
			(stroke
				(width 0.1524)
				(type default)
			)
			(layer "F.SilkS")
		)
		(fp_line
			(start -0.7874 0.4064)
			(end -0.7874 -0.4064)
			(stroke
				(width 0.1524)
				(type default)
			)
			(layer "F.SilkS")
		)
		(fp_line
			(start -0.7874 -0.4064)
			(end 0.7874 -0.4064)
			(stroke
				(width 0.1524)
				(type default)
			)
			(layer "F.SilkS")
		)
		(fp_line
			(start 0.67945 0.3048)
			(end 0.120396 0.3048)
			(stroke
				(width 0.1)
				(type default)
			)
			(layer "F.Fab")
		)
		(fp_line
			(start 0.67945 -0.3048)
			(end 0.67945 0.3048)
			(stroke
				(width 0.1)
				(type default)
			)
			(layer "F.Fab")
		)
		(fp_line
			(start 0.12065 -0.2794)
			(end 0.12065 -0.3048)
			(stroke
				(width 0.1)
				(type default)
			)
			(layer "F.Fab")
		)
		(fp_line
			(start 0.12065 -0.3048)
			(end 0.67945 -0.3048)
			(stroke
				(width 0.1)
				(type default)
			)
			(layer "F.Fab")
		)
		(fp_line
			(start 0.120396 0.3048)
			(end 0.120396 0.2794)
			(stroke
				(width 0.1)
				(type default)
			)
			(layer "F.Fab")
		)
		(fp_line
			(start 0.120396 0.2794)
			(end -0.12065 0.2794)
			(stroke
				(width 0.1)
				(type default)
			)
			(layer "F.Fab")
		)
		(fp_line
			(start -0.12065 0.3048)
			(end -0.67945 0.3048)
			(stroke
				(width 0.1)
				(type default)
			)
			(layer "F.Fab")
		)
		(fp_line
			(start -0.12065 0.2794)
			(end -0.12065 0.3048)
			(stroke
				(width 0.1)
				(type default)
			)
			(layer "F.Fab")
		)
		(fp_line
			(start -0.12065 -0.2794)
			(end 0.12065 -0.2794)
			(stroke
				(width 0.1)
				(type default)
			)
			(layer "F.Fab")
		)
		(fp_line
			(start -0.12065 -0.305054)
			(end -0.12065 -0.2794)
			(stroke
				(width 0.1)
				(type default)
			)
			(layer "F.Fab")
		)
		(fp_line
			(start -0.67945 0.3048)
			(end -0.67945 -0.305054)
			(stroke
				(width 0.1)
				(type default)
			)
			(layer "F.Fab")
		)
		(fp_line
			(start -0.67945 -0.305054)
			(end -0.12065 -0.305054)
			(stroke
				(width 0.1)
				(type default)
			)
			(layer "F.Fab")
		)
		(pad "1" smd circle
			(at -0.40005 0 180)
			(size 0 0)
			(layers "F.Cu" "F.Mask" "F.Paste")
			(net "SMB_LM75_0_3V3AUX_SDA_R")
		)
		(pad "2" smd circle
			(at 0.40005 0 180)
			(size 0 0)
			(layers "F.Cu" "F.Mask" "F.Paste")
			(net "SMB_LM75_0_3V3AUX_SDA")
		)
	)
	(footprint ""
		(layer "F.Cu")
		(at 439.272172 -32.173418 90)
		(property "Reference" "PC2156"
			(at 0 0 90)
			(layer "F.SilkS")
			(hide yes)
			(effects
				(font
					(size 1.27 1.27)
				)
			)
		)
		(property "Value" ""
			(at 0 0 90)
			(layer "F.Fab")
			(effects
				(font
					(size 1.27 1.27)
				)
			)
		)
		(duplicate_pad_numbers_are_jumpers no)
		(fp_line
			(start 0.7874 -0.4064)
			(end 0.7874 0.4064)
			(stroke
				(width 0.1524)
				(type default)
			)
			(layer "F.SilkS")
		)
		(fp_line
			(start -0.7874 -0.4064)
			(end 0.7874 -0.4064)
			(stroke
				(width 0.1524)
				(type default)
			)
			(layer "F.SilkS")
		)
		(fp_line
			(start 0.7874 0.4064)
			(end -0.7874 0.4064)
			(stroke
				(width 0.1524)
				(type default)
			)
			(layer "F.SilkS")
		)
		(fp_line
			(start -0.7874 0.4064)
			(end -0.7874 -0.4064)
			(stroke
				(width 0.1524)
				(type default)
			)
			(layer "F.SilkS")
		)
		(fp_line
			(start -0.12065 -0.305054)
			(end -0.12065 -0.2794)
			(stroke
				(width 0.1)
				(type default)
			)
			(layer "F.Fab")
		)
		(fp_line
			(start -0.67945 -0.305054)
			(end -0.12065 -0.305054)
			(stroke
				(width 0.1)
				(type default)
			)
			(layer "F.Fab")
		)
		(fp_line
			(start 0.67945 -0.3048)
			(end 0.67945 0.3048)
			(stroke
				(width 0.1)
				(type default)
			)
			(layer "F.Fab")
		)
		(fp_line
			(start 0.12065 -0.3048)
			(end 0.67945 -0.3048)
			(stroke
				(width 0.1)
				(type default)
			)
			(layer "F.Fab")
		)
		(fp_line
			(start 0.12065 -0.2794)
			(end 0.12065 -0.3048)
			(stroke
				(width 0.1)
				(type default)
			)
			(layer "F.Fab")
		)
		(fp_line
			(start -0.12065 -0.2794)
			(end 0.12065 -0.2794)
			(stroke
				(width 0.1)
				(type default)
			)
			(layer "F.Fab")
		)
		(fp_line
			(start 0.120396 0.2794)
			(end -0.12065 0.2794)
			(stroke
				(width 0.1)
				(type default)
			)
			(layer "F.Fab")
		)
		(fp_line
			(start -0.12065 0.2794)
			(end -0.12065 0.3048)
			(stroke
				(width 0.1)
				(type default)
			)
			(layer "F.Fab")
		)
		(fp_line
			(start 0.67945 0.3048)
			(end 0.120396 0.3048)
			(stroke
				(width 0.1)
				(type default)
			)
			(layer "F.Fab")
		)
		(fp_line
			(start 0.120396 0.3048)
			(end 0.120396 0.2794)
			(stroke
				(width 0.1)
				(type default)
			)
			(layer "F.Fab")
		)
		(fp_line
			(start -0.12065 0.3048)
			(end -0.67945 0.3048)
			(stroke
				(width 0.1)
				(type default)
			)
			(layer "F.Fab")
		)
		(fp_line
			(start -0.67945 0.3048)
			(end -0.67945 -0.305054)
			(stroke
				(width 0.1)
				(type default)
			)
			(layer "F.Fab")
		)
		(pad "1" smd circle
			(at -0.40005 0 90)
			(size 0 0)
			(layers "F.Cu" "F.Mask" "F.Paste")
			(net "P12V_OCP_IMON_1")
		)
		(pad "2" smd circle
			(at 0.40005 0 90)
			(size 0 0)
			(layers "F.Cu" "F.Mask" "F.Paste")
			(net "GND")
		)
	)
	(footprint ""
		(layer "F.Cu")
		(at 338.56295 -341.729822 -90)
		(property "Reference" "PC256"
			(at 0 0 270)
			(layer "F.SilkS")
			(hide yes)
			(effects
				(font
					(size 1.27 1.27)
				)
			)
		)
		(property "Value" ""
			(at 0 0 270)
			(layer "F.Fab")
			(effects
				(font
					(size 1.27 1.27)
				)
			)
		)
		(duplicate_pad_numbers_are_jumpers no)
		(fp_line
			(start -0.7874 0.4064)
			(end -0.7874 -0.4064)
			(stroke
				(width 0.1524)
				(type default)
			)
			(layer "F.SilkS")
		)
		(fp_line
			(start 0.7874 0.4064)
			(end -0.7874 0.4064)
			(stroke
				(width 0.1524)
				(type default)
			)
			(layer "F.SilkS")
		)
		(fp_line
			(start -0.7874 -0.4064)
			(end 0.7874 -0.4064)
			(stroke
				(width 0.1524)
				(type default)
			)
			(layer "F.SilkS")
		)
		(fp_line
			(start 0.7874 -0.4064)
			(end 0.7874 0.4064)
			(stroke
				(width 0.1524)
				(type default)
			)
			(layer "F.SilkS")
		)
		(fp_line
			(start -0.67945 0.3048)
			(end -0.67945 -0.305054)
			(stroke
				(width 0.1)
				(type default)
			)
			(layer "F.Fab")
		)
		(fp_line
			(start -0.12065 0.3048)
			(end -0.67945 0.3048)
			(stroke
				(width 0.1)
				(type default)
			)
			(layer "F.Fab")
		)
		(fp_line
			(start 0.120396 0.3048)
			(end 0.120396 0.2794)
			(stroke
				(width 0.1)
				(type default)
			)
			(layer "F.Fab")
		)
		(fp_line
			(start 0.67945 0.3048)
			(end 0.120396 0.3048)
			(stroke
				(width 0.1)
				(type default)
			)
			(layer "F.Fab")
		)
		(fp_line
			(start -0.12065 0.2794)
			(end -0.12065 0.3048)
			(stroke
				(width 0.1)
				(type default)
			)
			(layer "F.Fab")
		)
		(fp_line
			(start 0.120396 0.2794)
			(end -0.12065 0.2794)
			(stroke
				(width 0.1)
				(type default)
			)
			(layer "F.Fab")
		)
		(fp_line
			(start -0.12065 -0.2794)
			(end 0.12065 -0.2794)
			(stroke
				(width 0.1)
				(type default)
			)
			(layer "F.Fab")
		)
		(fp_line
			(start 0.12065 -0.2794)
			(end 0.12065 -0.3048)
			(stroke
				(width 0.1)
				(type default)
			)
			(layer "F.Fab")
		)
		(fp_line
			(start 0.12065 -0.3048)
			(end 0.67945 -0.3048)
			(stroke
				(width 0.1)
				(type default)
			)
			(layer "F.Fab")
		)
		(fp_line
			(start 0.67945 -0.3048)
			(end 0.67945 0.3048)
			(stroke
				(width 0.1)
				(type default)
			)
			(layer "F.Fab")
		)
		(fp_line
			(start -0.67945 -0.305054)
			(end -0.12065 -0.305054)
			(stroke
				(width 0.1)
				(type default)
			)
			(layer "F.Fab")
		)
		(fp_line
			(start -0.12065 -0.305054)
			(end -0.12065 -0.2794)
			(stroke
				(width 0.1)
				(type default)
			)
			(layer "F.Fab")
		)
		(pad "1" smd circle
			(at -0.40005 0 270)
			(size 0 0)
			(layers "F.Cu" "F.Mask" "F.Paste")
			(net "SW_PVCCIN_CPU0_BOOT6_R")
		)
		(pad "2" smd circle
			(at 0.40005 0 270)
			(size 0 0)
			(layers "F.Cu" "F.Mask" "F.Paste")
			(net "SW_PVCCIN_CPU0_BOOTR6")
		)
	)
	(footprint ""
		(layer "F.Cu")
		(at 458.720444 -70.271386 -90)
		(property "Reference" "PC2261"
			(at 0 0 270)
			(layer "F.SilkS")
			(hide yes)
			(effects
				(font
					(size 1.27 1.27)
				)
			)
		)
		(property "Value" ""
			(at 0 0 270)
			(layer "F.Fab")
			(effects
				(font
					(size 1.27 1.27)
				)
			)
		)
		(duplicate_pad_numbers_are_jumpers no)
		(fp_line
			(start -1.524 0.762)
			(end -1.524 -0.762)
			(stroke
				(width 0.1524)
				(type default)
			)
			(layer "F.SilkS")
		)
		(fp_line
			(start 1.524 0.762)
			(end -1.524 0.762)
			(stroke
				(width 0.1524)
				(type default)
			)
			(layer "F.SilkS")
		)
		(fp_line
			(start -1.524 -0.762)
			(end 1.524 -0.762)
			(stroke
				(width 0.1524)
				(type default)
			)
			(layer "F.SilkS")
		)
		(fp_line
			(start 1.524 -0.762)
			(end 1.524 0.762)
			(stroke
				(width 0.1524)
				(type default)
			)
			(layer "F.SilkS")
		)
		(fp_line
			(start -1.1049 0.724916)
			(end 1.1049 0.724916)
			(stroke
				(width 0.1)
				(type default)
			)
			(layer "F.Fab")
		)
		(fp_line
			(start 1.1049 0.724916)
			(end 1.1049 -0.724916)
			(stroke
				(width 0.1)
				(type default)
			)
			(layer "F.Fab")
		)
		(fp_line
			(start -1.1049 -0.724916)
			(end -1.1049 0.724916)
			(stroke
				(width 0.1)
				(type default)
			)
			(layer "F.Fab")
		)
		(fp_line
			(start 1.1049 -0.724916)
			(end -1.1049 -0.724916)
			(stroke
				(width 0.1)
				(type default)
			)
			(layer "F.Fab")
		)
		(pad "1" smd rect
			(at -0.889 0 90)
			(size 1.016 1.27)
			(layers "F.Cu" "F.Mask" "F.Paste")
			(net "SW_P3V3_AUX_FLT")
		)
		(pad "2" smd rect
			(at 0.889 0 90)
			(size 1.016 1.27)
			(layers "F.Cu" "F.Mask" "F.Paste")
			(net "GND")
		)
	)
	(footprint ""
		(layer "F.Cu")
		(at 30.49524 -122.380502 90)
		(property "Reference" "R2450"
			(at 0 0 90)
			(layer "F.SilkS")
			(hide yes)
			(effects
				(font
					(size 1.27 1.27)
				)
			)
		)
		(property "Value" ""
			(at 0 0 90)
			(layer "F.Fab")
			(effects
				(font
					(size 1.27 1.27)
				)
			)
		)
		(duplicate_pad_numbers_are_jumpers no)
		(fp_line
			(start 0.7874 -0.4064)
			(end 0.7874 0.4064)
			(stroke
				(width 0.1524)
				(type default)
			)
			(layer "F.SilkS")
		)
		(fp_line
			(start -0.7874 -0.4064)
			(end 0.7874 -0.4064)
			(stroke
				(width 0.1524)
				(type default)
			)
			(layer "F.SilkS")
		)
		(fp_line
			(start 0.7874 0.4064)
			(end -0.7874 0.4064)
			(stroke
				(width 0.1524)
				(type default)
			)
			(layer "F.SilkS")
		)
		(fp_line
			(start -0.7874 0.4064)
			(end -0.7874 -0.4064)
			(stroke
				(width 0.1524)
				(type default)
			)
			(layer "F.SilkS")
		)
		(fp_line
			(start -0.12065 -0.305054)
			(end -0.12065 -0.2794)
			(stroke
				(width 0.1)
				(type default)
			)
			(layer "F.Fab")
		)
		(fp_line
			(start -0.67945 -0.305054)
			(end -0.12065 -0.305054)
			(stroke
				(width 0.1)
				(type default)
			)
			(layer "F.Fab")
		)
		(fp_line
			(start 0.67945 -0.3048)
			(end 0.67945 0.3048)
			(stroke
				(width 0.1)
				(type default)
			)
			(layer "F.Fab")
		)
		(fp_line
			(start 0.12065 -0.3048)
			(end 0.67945 -0.3048)
			(stroke
				(width 0.1)
				(type default)
			)
			(layer "F.Fab")
		)
		(fp_line
			(start 0.12065 -0.2794)
			(end 0.12065 -0.3048)
			(stroke
				(width 0.1)
				(type default)
			)
			(layer "F.Fab")
		)
		(fp_line
			(start -0.12065 -0.2794)
			(end 0.12065 -0.2794)
			(stroke
				(width 0.1)
				(type default)
			)
			(layer "F.Fab")
		)
		(fp_line
			(start 0.120396 0.2794)
			(end -0.12065 0.2794)
			(stroke
				(width 0.1)
				(type default)
			)
			(layer "F.Fab")
		)
		(fp_line
			(start -0.12065 0.2794)
			(end -0.12065 0.3048)
			(stroke
				(width 0.1)
				(type default)
			)
			(layer "F.Fab")
		)
		(fp_line
			(start 0.67945 0.3048)
			(end 0.120396 0.3048)
			(stroke
				(width 0.1)
				(type default)
			)
			(layer "F.Fab")
		)
		(fp_line
			(start 0.120396 0.3048)
			(end 0.120396 0.2794)
			(stroke
				(width 0.1)
				(type default)
			)
			(layer "F.Fab")
		)
		(fp_line
			(start -0.12065 0.3048)
			(end -0.67945 0.3048)
			(stroke
				(width 0.1)
				(type default)
			)
			(layer "F.Fab")
		)
		(fp_line
			(start -0.67945 0.3048)
			(end -0.67945 -0.305054)
			(stroke
				(width 0.1)
				(type default)
			)
			(layer "F.Fab")
		)
		(pad "1" smd circle
			(at -0.40005 0 90)
			(size 0 0)
			(layers "F.Cu" "F.Mask" "F.Paste")
			(net "SMB_VR_3V3AUX_SDA")
		)
		(pad "2" smd circle
			(at 0.40005 0 90)
			(size 0 0)
			(layers "F.Cu" "F.Mask" "F.Paste")
			(net "SMB_VR_3V3AUX_SDA_R1")
		)
	)
)
